(kicad_pcb
	(version 20260206)
	(generator "pcbnew")
	(generator_version "10.0")
	(general
		(thickness 1.6)
		(legacy_teardrops no)
	)
	(paper "A4")
	(title_block
		(title "04192023_DAF0TMB3IC0_F0TG_MB_C_brd_V02_OCP.brd")
		(comment 1 "Grand Teton / footprints 4596-4603 of 8354")
	)
	(layers
		(0 "F.Cu" signal "TOP")
		(4 "In1.Cu" signal "GND")
		(6 "In2.Cu" signal "IN1")
		(8 "In3.Cu" signal "GND1")
		(10 "In4.Cu" signal "IN2")
		(12 "In5.Cu" signal "GND2")
		(14 "In6.Cu" signal "IN3")
		(16 "In7.Cu" signal "GND3")
		(18 "In8.Cu" signal "VCC")
		(20 "In9.Cu" signal "VCC1")
		(22 "In10.Cu" signal "GND4")
		(24 "In11.Cu" signal "IN4")
		(26 "In12.Cu" signal "GND5")
		(28 "In13.Cu" signal "IN5")
		(30 "In14.Cu" signal "GND6")
		(32 "In15.Cu" signal "IN6")
		(34 "In16.Cu" signal "GND7")
		(2 "B.Cu" signal "BOTTOM")
		(9 "F.Adhes" user "F.Adhesive")
		(11 "B.Adhes" user "B.Adhesive")
		(13 "F.Paste" user "Package Geometry/Pastemask Top")
		(15 "B.Paste" user "Package Geometry/Pastemask Bottom")
		(5 "F.SilkS" user "Ref Des/Silkscreen Top")
		(7 "B.SilkS" user "Ref Des/Silkscreen Bottom")
		(1 "F.Mask" user "Board Geometry/Soldermask Top")
		(3 "B.Mask" user "Board Geometry/Soldermask Bottom")
		(17 "Dwgs.User" user "User.Drawings")
		(19 "Cmts.User" user "User.Comments")
		(21 "Eco1.User" user "User.Eco1")
		(23 "Eco2.User" user "User.Eco2")
		(25 "Edge.Cuts" user "Board Geometry/Outline")
		(27 "Margin" user)
		(31 "F.CrtYd" user "Package Geometry/Place Bound Top")
		(29 "B.CrtYd" user "Package Geometry/Place Bound Bottom")
		(35 "F.Fab" user "Ref Des/Assembly Top")
		(33 "B.Fab" user "Ref Des/Assembly Bottom")
	)
	(footprint ""
		(layer "F.Cu")
		(at 226.0981 -401.988782 180)
		(property "Reference" "PR3991"
			(at 0 0 180)
			(layer "F.SilkS")
			(hide yes)
			(effects
				(font
					(size 1.27 1.27)
				)
			)
		)
		(property "Value" ""
			(at 0 0 180)
			(layer "F.Fab")
			(effects
				(font
					(size 1.27 1.27)
				)
			)
		)
		(duplicate_pad_numbers_are_jumpers no)
		(fp_line
			(start 0.7874 0.4064)
			(end -0.7874 0.4064)
			(stroke
				(width 0.1524)
				(type default)
			)
			(layer "F.SilkS")
		)
		(fp_line
			(start 0.7874 -0.4064)
			(end 0.7874 0.4064)
			(stroke
				(width 0.1524)
				(type default)
			)
			(layer "F.SilkS")
		)
		(fp_line
			(start -0.7874 0.4064)
			(end -0.7874 -0.4064)
			(stroke
				(width 0.1524)
				(type default)
			)
			(layer "F.SilkS")
		)
		(fp_line
			(start -0.7874 -0.4064)
			(end 0.7874 -0.4064)
			(stroke
				(width 0.1524)
				(type default)
			)
			(layer "F.SilkS")
		)
		(fp_line
			(start 0.67945 0.3048)
			(end 0.120396 0.3048)
			(stroke
				(width 0.1)
				(type default)
			)
			(layer "F.Fab")
		)
		(fp_line
			(start 0.67945 -0.3048)
			(end 0.67945 0.3048)
			(stroke
				(width 0.1)
				(type default)
			)
			(layer "F.Fab")
		)
		(fp_line
			(start 0.12065 -0.2794)
			(end 0.12065 -0.3048)
			(stroke
				(width 0.1)
				(type default)
			)
			(layer "F.Fab")
		)
		(fp_line
			(start 0.12065 -0.3048)
			(end 0.67945 -0.3048)
			(stroke
				(width 0.1)
				(type default)
			)
			(layer "F.Fab")
		)
		(fp_line
			(start 0.120396 0.3048)
			(end 0.120396 0.2794)
			(stroke
				(width 0.1)
				(type default)
			)
			(layer "F.Fab")
		)
		(fp_line
			(start 0.120396 0.2794)
			(end -0.12065 0.2794)
			(stroke
				(width 0.1)
				(type default)
			)
			(layer "F.Fab")
		)
		(fp_line
			(start -0.12065 0.3048)
			(end -0.67945 0.3048)
			(stroke
				(width 0.1)
				(type default)
			)
			(layer "F.Fab")
		)
		(fp_line
			(start -0.12065 0.2794)
			(end -0.12065 0.3048)
			(stroke
				(width 0.1)
				(type default)
			)
			(layer "F.Fab")
		)
		(fp_line
			(start -0.12065 -0.2794)
			(end 0.12065 -0.2794)
			(stroke
				(width 0.1)
				(type default)
			)
			(layer "F.Fab")
		)
		(fp_line
			(start -0.12065 -0.305054)
			(end -0.12065 -0.2794)
			(stroke
				(width 0.1)
				(type default)
			)
			(layer "F.Fab")
		)
		(fp_line
			(start -0.67945 0.3048)
			(end -0.67945 -0.305054)
			(stroke
				(width 0.1)
				(type default)
			)
			(layer "F.Fab")
		)
		(fp_line
			(start -0.67945 -0.305054)
			(end -0.12065 -0.305054)
			(stroke
				(width 0.1)
				(type default)
			)
			(layer "F.Fab")
		)
		(pad "1" smd circle
			(at -0.40005 0 180)
			(size 0 0)
			(layers "F.Cu" "F.Mask" "F.Paste")
			(net "HSC_IMON")
		)
		(pad "2" smd circle
			(at 0.40005 0 180)
			(size 0 0)
			(layers "F.Cu" "F.Mask" "F.Paste")
			(net "AGND_HSC")
		)
	)
	(footprint ""
		(layer "F.Cu")
		(at 315.341 -357.251 180)
		(property "Reference" "PC71"
			(at 0 0 180)
			(layer "F.SilkS")
			(hide yes)
			(effects
				(font
					(size 1.27 1.27)
				)
			)
		)
		(property "Value" ""
			(at 0 0 180)
			(layer "F.Fab")
			(effects
				(font
					(size 1.27 1.27)
				)
			)
		)
		(duplicate_pad_numbers_are_jumpers no)
		(fp_line
			(start 0.7874 0.4064)
			(end -0.7874 0.4064)
			(stroke
				(width 0.1524)
				(type default)
			)
			(layer "F.SilkS")
		)
		(fp_line
			(start 0.7874 -0.4064)
			(end 0.7874 0.4064)
			(stroke
				(width 0.1524)
				(type default)
			)
			(layer "F.SilkS")
		)
		(fp_line
			(start -0.7874 0.4064)
			(end -0.7874 -0.4064)
			(stroke
				(width 0.1524)
				(type default)
			)
			(layer "F.SilkS")
		)
		(fp_line
			(start -0.7874 -0.4064)
			(end 0.7874 -0.4064)
			(stroke
				(width 0.1524)
				(type default)
			)
			(layer "F.SilkS")
		)
		(fp_line
			(start 0.67945 0.3048)
			(end 0.120396 0.3048)
			(stroke
				(width 0.1)
				(type default)
			)
			(layer "F.Fab")
		)
		(fp_line
			(start 0.67945 -0.3048)
			(end 0.67945 0.3048)
			(stroke
				(width 0.1)
				(type default)
			)
			(layer "F.Fab")
		)
		(fp_line
			(start 0.12065 -0.2794)
			(end 0.12065 -0.3048)
			(stroke
				(width 0.1)
				(type default)
			)
			(layer "F.Fab")
		)
		(fp_line
			(start 0.12065 -0.3048)
			(end 0.67945 -0.3048)
			(stroke
				(width 0.1)
				(type default)
			)
			(layer "F.Fab")
		)
		(fp_line
			(start 0.120396 0.3048)
			(end 0.120396 0.2794)
			(stroke
				(width 0.1)
				(type default)
			)
			(layer "F.Fab")
		)
		(fp_line
			(start 0.120396 0.2794)
			(end -0.12065 0.2794)
			(stroke
				(width 0.1)
				(type default)
			)
			(layer "F.Fab")
		)
		(fp_line
			(start -0.12065 0.3048)
			(end -0.67945 0.3048)
			(stroke
				(width 0.1)
				(type default)
			)
			(layer "F.Fab")
		)
		(fp_line
			(start -0.12065 0.2794)
			(end -0.12065 0.3048)
			(stroke
				(width 0.1)
				(type default)
			)
			(layer "F.Fab")
		)
		(fp_line
			(start -0.12065 -0.2794)
			(end 0.12065 -0.2794)
			(stroke
				(width 0.1)
				(type default)
			)
			(layer "F.Fab")
		)
		(fp_line
			(start -0.12065 -0.305054)
			(end -0.12065 -0.2794)
			(stroke
				(width 0.1)
				(type default)
			)
			(layer "F.Fab")
		)
		(fp_line
			(start -0.67945 0.3048)
			(end -0.67945 -0.305054)
			(stroke
				(width 0.1)
				(type default)
			)
			(layer "F.Fab")
		)
		(fp_line
			(start -0.67945 -0.305054)
			(end -0.12065 -0.305054)
			(stroke
				(width 0.1)
				(type default)
			)
			(layer "F.Fab")
		)
		(pad "1" smd circle
			(at -0.40005 0 180)
			(size 0 0)
			(layers "F.Cu" "F.Mask" "F.Paste")
			(net "VSENSE_PVDDIO_P0_VSEN1")
		)
		(pad "2" smd circle
			(at 0.40005 0 180)
			(size 0 0)
			(layers "F.Cu" "F.Mask" "F.Paste")
			(net "VSENSE_VSS_SENSE_B_P0")
		)
	)
	(footprint ""
		(layer "F.Cu")
		(at 90.209878 -143.86941)
		(property "Reference" "R8184"
			(at 0 0 0)
			(layer "F.SilkS")
			(hide yes)
			(effects
				(font
					(size 1.27 1.27)
				)
			)
		)
		(property "Value" ""
			(at 0 0 0)
			(layer "F.Fab")
			(effects
				(font
					(size 1.27 1.27)
				)
			)
		)
		(duplicate_pad_numbers_are_jumpers no)
		(fp_line
			(start -0.7874 -0.4064)
			(end 0.7874 -0.4064)
			(stroke
				(width 0.1524)
				(type default)
			)
			(layer "F.SilkS")
		)
		(fp_line
			(start -0.7874 0.4064)
			(end -0.7874 -0.4064)
			(stroke
				(width 0.1524)
				(type default)
			)
			(layer "F.SilkS")
		)
		(fp_line
			(start 0.7874 -0.4064)
			(end 0.7874 0.4064)
			(stroke
				(width 0.1524)
				(type default)
			)
			(layer "F.SilkS")
		)
		(fp_line
			(start 0.7874 0.4064)
			(end -0.7874 0.4064)
			(stroke
				(width 0.1524)
				(type default)
			)
			(layer "F.SilkS")
		)
		(fp_line
			(start -0.67945 -0.305054)
			(end -0.12065 -0.305054)
			(stroke
				(width 0.1)
				(type default)
			)
			(layer "F.Fab")
		)
		(fp_line
			(start -0.67945 0.3048)
			(end -0.67945 -0.305054)
			(stroke
				(width 0.1)
				(type default)
			)
			(layer "F.Fab")
		)
		(fp_line
			(start -0.12065 -0.305054)
			(end -0.12065 -0.2794)
			(stroke
				(width 0.1)
				(type default)
			)
			(layer "F.Fab")
		)
		(fp_line
			(start -0.12065 -0.2794)
			(end 0.12065 -0.2794)
			(stroke
				(width 0.1)
				(type default)
			)
			(layer "F.Fab")
		)
		(fp_line
			(start -0.12065 0.2794)
			(end -0.12065 0.3048)
			(stroke
				(width 0.1)
				(type default)
			)
			(layer "F.Fab")
		)
		(fp_line
			(start -0.12065 0.3048)
			(end -0.67945 0.3048)
			(stroke
				(width 0.1)
				(type default)
			)
			(layer "F.Fab")
		)
		(fp_line
			(start 0.120396 0.2794)
			(end -0.12065 0.2794)
			(stroke
				(width 0.1)
				(type default)
			)
			(layer "F.Fab")
		)
		(fp_line
			(start 0.120396 0.3048)
			(end 0.120396 0.2794)
			(stroke
				(width 0.1)
				(type default)
			)
			(layer "F.Fab")
		)
		(fp_line
			(start 0.12065 -0.3048)
			(end 0.67945 -0.3048)
			(stroke
				(width 0.1)
				(type default)
			)
			(layer "F.Fab")
		)
		(fp_line
			(start 0.12065 -0.2794)
			(end 0.12065 -0.3048)
			(stroke
				(width 0.1)
				(type default)
			)
			(layer "F.Fab")
		)
		(fp_line
			(start 0.67945 -0.3048)
			(end 0.67945 0.3048)
			(stroke
				(width 0.1)
				(type default)
			)
			(layer "F.Fab")
		)
		(fp_line
			(start 0.67945 0.3048)
			(end 0.120396 0.3048)
			(stroke
				(width 0.1)
				(type default)
			)
			(layer "F.Fab")
		)
		(pad "1" smd circle
			(at -0.40005 0)
			(size 0 0)
			(layers "F.Cu" "F.Mask" "F.Paste")
			(net "PVDD18_S5_P1")
		)
		(pad "2" smd circle
			(at 0.40005 0)
			(size 0 0)
			(layers "F.Cu" "F.Mask" "F.Paste")
			(net "PVDDCR_CPU0_P1_RESET_N_R")
		)
	)
	(footprint ""
		(layer "F.Cu")
		(at 18.702782 -137.976102)
		(property "Reference" "R3338"
			(at 0 0 0)
			(layer "F.SilkS")
			(hide yes)
			(effects
				(font
					(size 1.27 1.27)
				)
			)
		)
		(property "Value" ""
			(at 0 0 0)
			(layer "F.Fab")
			(effects
				(font
					(size 1.27 1.27)
				)
			)
		)
		(duplicate_pad_numbers_are_jumpers no)
		(fp_line
			(start -0.7874 -0.4064)
			(end 0.7874 -0.4064)
			(stroke
				(width 0.1524)
				(type default)
			)
			(layer "F.SilkS")
		)
		(fp_line
			(start -0.7874 0.4064)
			(end -0.7874 -0.4064)
			(stroke
				(width 0.1524)
				(type default)
			)
			(layer "F.SilkS")
		)
		(fp_line
			(start 0.7874 -0.4064)
			(end 0.7874 0.4064)
			(stroke
				(width 0.1524)
				(type default)
			)
			(layer "F.SilkS")
		)
		(fp_line
			(start 0.7874 0.4064)
			(end -0.7874 0.4064)
			(stroke
				(width 0.1524)
				(type default)
			)
			(layer "F.SilkS")
		)
		(fp_line
			(start -0.67945 -0.305054)
			(end -0.12065 -0.305054)
			(stroke
				(width 0.1)
				(type default)
			)
			(layer "F.Fab")
		)
		(fp_line
			(start -0.67945 0.3048)
			(end -0.67945 -0.305054)
			(stroke
				(width 0.1)
				(type default)
			)
			(layer "F.Fab")
		)
		(fp_line
			(start -0.12065 -0.305054)
			(end -0.12065 -0.2794)
			(stroke
				(width 0.1)
				(type default)
			)
			(layer "F.Fab")
		)
		(fp_line
			(start -0.12065 -0.2794)
			(end 0.12065 -0.2794)
			(stroke
				(width 0.1)
				(type default)
			)
			(layer "F.Fab")
		)
		(fp_line
			(start -0.12065 0.2794)
			(end -0.12065 0.3048)
			(stroke
				(width 0.1)
				(type default)
			)
			(layer "F.Fab")
		)
		(fp_line
			(start -0.12065 0.3048)
			(end -0.67945 0.3048)
			(stroke
				(width 0.1)
				(type default)
			)
			(layer "F.Fab")
		)
		(fp_line
			(start 0.120396 0.2794)
			(end -0.12065 0.2794)
			(stroke
				(width 0.1)
				(type default)
			)
			(layer "F.Fab")
		)
		(fp_line
			(start 0.120396 0.3048)
			(end 0.120396 0.2794)
			(stroke
				(width 0.1)
				(type default)
			)
			(layer "F.Fab")
		)
		(fp_line
			(start 0.12065 -0.3048)
			(end 0.67945 -0.3048)
			(stroke
				(width 0.1)
				(type default)
			)
			(layer "F.Fab")
		)
		(fp_line
			(start 0.12065 -0.2794)
			(end 0.12065 -0.3048)
			(stroke
				(width 0.1)
				(type default)
			)
			(layer "F.Fab")
		)
		(fp_line
			(start 0.67945 -0.3048)
			(end 0.67945 0.3048)
			(stroke
				(width 0.1)
				(type default)
			)
			(layer "F.Fab")
		)
		(fp_line
			(start 0.67945 0.3048)
			(end 0.120396 0.3048)
			(stroke
				(width 0.1)
				(type default)
			)
			(layer "F.Fab")
		)
		(pad "1" smd circle
			(at -0.40005 0)
			(size 0 0)
			(layers "F.Cu" "F.Mask" "F.Paste")
			(net "CLK_100M_GPU_FPGA_DN_R")
		)
		(pad "2" smd circle
			(at 0.40005 0)
			(size 0 0)
			(layers "F.Cu" "F.Mask" "F.Paste")
			(net "CLK_100M_GPU_FPGA_DN")
		)
	)
	(footprint ""
		(layer "F.Cu")
		(at 331.793342 -393.04468)
		(property "Reference" "R1029"
			(at 0 0 0)
			(layer "F.SilkS")
			(hide yes)
			(effects
				(font
					(size 1.27 1.27)
				)
			)
		)
		(property "Value" ""
			(at 0 0 0)
			(layer "F.Fab")
			(effects
				(font
					(size 1.27 1.27)
				)
			)
		)
		(duplicate_pad_numbers_are_jumpers no)
		(fp_line
			(start -0.32512 -0.175006)
			(end 0.32512 -0.175006)
			(stroke
				(width 0.1)
				(type default)
			)
			(layer "F.Fab")
		)
		(fp_line
			(start -0.32512 0.175006)
			(end -0.32512 -0.175006)
			(stroke
				(width 0.1)
				(type default)
			)
			(layer "F.Fab")
		)
		(fp_line
			(start 0.32512 -0.175006)
			(end 0.32512 0.175006)
			(stroke
				(width 0.1)
				(type default)
			)
			(layer "F.Fab")
		)
		(fp_line
			(start 0.32512 0.175006)
			(end -0.32512 0.175006)
			(stroke
				(width 0.1)
				(type default)
			)
			(layer "F.Fab")
		)
		(pad "1" smd rect
			(at -0.2667 0)
			(size 0.3048 0.381)
			(layers "F.Cu" "F.Mask" "F.Paste")
			(net "GPIO3_RT_CPU0_P1")
		)
		(pad "2" smd rect
			(at 0.2667 0 180)
			(size 0.3048 0.381)
			(layers "F.Cu" "F.Mask" "F.Paste")
			(net "GND")
		)
	)
	(footprint ""
		(layer "F.Cu")
		(at 142.155672 -386.951474)
		(property "Reference" "R620"
			(at 0 0 0)
			(layer "F.SilkS")
			(hide yes)
			(effects
				(font
					(size 1.27 1.27)
				)
			)
		)
		(property "Value" ""
			(at 0 0 0)
			(layer "F.Fab")
			(effects
				(font
					(size 1.27 1.27)
				)
			)
		)
		(duplicate_pad_numbers_are_jumpers no)
		(fp_line
			(start -0.32512 -0.175006)
			(end 0.32512 -0.175006)
			(stroke
				(width 0.1)
				(type default)
			)
			(layer "F.Fab")
		)
		(fp_line
			(start -0.32512 0.175006)
			(end -0.32512 -0.175006)
			(stroke
				(width 0.1)
				(type default)
			)
			(layer "F.Fab")
		)
		(fp_line
			(start 0.32512 -0.175006)
			(end 0.32512 0.175006)
			(stroke
				(width 0.1)
				(type default)
			)
			(layer "F.Fab")
		)
		(fp_line
			(start 0.32512 0.175006)
			(end -0.32512 0.175006)
			(stroke
				(width 0.1)
				(type default)
			)
			(layer "F.Fab")
		)
		(pad "1" smd rect
			(at -0.2667 0)
			(size 0.3048 0.381)
			(layers "F.Cu" "F.Mask" "F.Paste")
			(net "CLK_100M_RETIMER_CPU1_P2_R_DN")
		)
		(pad "2" smd rect
			(at 0.2667 0 180)
			(size 0.3048 0.381)
			(layers "F.Cu" "F.Mask" "F.Paste")
			(net "CLK_100M_RETIMER_CPU1_P2_DN")
		)
	)
	(footprint ""
		(layer "F.Cu")
		(at 403.72284 -383.88163 -90)
		(property "Reference" "C861"
			(at 0 0 270)
			(layer "F.SilkS")
			(hide yes)
			(effects
				(font
					(size 1.27 1.27)
				)
			)
		)
		(property "Value" ""
			(at 0 0 270)
			(layer "F.Fab")
			(effects
				(font
					(size 1.27 1.27)
				)
			)
		)
		(duplicate_pad_numbers_are_jumpers no)
		(fp_line
			(start -0.299974 0.150114)
			(end -0.299974 -0.150114)
			(stroke
				(width 0.1)
				(type default)
			)
			(layer "F.Fab")
		)
		(fp_line
			(start 0.299974 0.150114)
			(end -0.299974 0.150114)
			(stroke
				(width 0.1)
				(type default)
			)
			(layer "F.Fab")
		)
		(fp_line
			(start -0.299974 -0.150114)
			(end 0.299974 -0.150114)
			(stroke
				(width 0.1)
				(type default)
			)
			(layer "F.Fab")
		)
		(fp_line
			(start 0.299974 -0.150114)
			(end 0.299974 0.150114)
			(stroke
				(width 0.1)
				(type default)
			)
			(layer "F.Fab")
		)
		(pad "1" smd rect
			(at -0.2667 0 270)
			(size 0.3048 0.381)
			(layers "F.Cu" "F.Mask" "F.Paste")
			(net "P5E_CPU0_P2_TX_C_DP<4>")
		)
		(pad "2" smd rect
			(at 0.2667 0 270)
			(size 0.3048 0.381)
			(layers "F.Cu" "F.Mask" "F.Paste")
			(net "P5E_CPU0_P2_TX_DP<4>")
		)
	)
	(footprint ""
		(layer "F.Cu")
		(at 225.171762 -69.318378 -90)
		(property "Reference" "R3979"
			(at 0 0 270)
			(layer "F.SilkS")
			(hide yes)
			(effects
				(font
					(size 1.27 1.27)
				)
			)
		)
		(property "Value" ""
			(at 0 0 270)
			(layer "F.Fab")
			(effects
				(font
					(size 1.27 1.27)
				)
			)
		)
		(duplicate_pad_numbers_are_jumpers no)
		(fp_line
			(start -0.7874 0.4064)
			(end -0.7874 -0.4064)
			(stroke
				(width 0.1524)
				(type default)
			)
			(layer "F.SilkS")
		)
		(fp_line
			(start 0.7874 0.4064)
			(end -0.7874 0.4064)
			(stroke
				(width 0.1524)
				(type default)
			)
			(layer "F.SilkS")
		)
		(fp_line
			(start -0.7874 -0.4064)
			(end 0.7874 -0.4064)
			(stroke
				(width 0.1524)
				(type default)
			)
			(layer "F.SilkS")
		)
		(fp_line
			(start 0.7874 -0.4064)
			(end 0.7874 0.4064)
			(stroke
				(width 0.1524)
				(type default)
			)
			(layer "F.SilkS")
		)
		(fp_line
			(start -0.67945 0.3048)
			(end -0.67945 -0.305054)
			(stroke
				(width 0.1)
				(type default)
			)
			(layer "F.Fab")
		)
		(fp_line
			(start -0.12065 0.3048)
			(end -0.67945 0.3048)
			(stroke
				(width 0.1)
				(type default)
			)
			(layer "F.Fab")
		)
		(fp_line
			(start 0.120396 0.3048)
			(end 0.120396 0.2794)
			(stroke
				(width 0.1)
				(type default)
			)
			(layer "F.Fab")
		)
		(fp_line
			(start 0.67945 0.3048)
			(end 0.120396 0.3048)
			(stroke
				(width 0.1)
				(type default)
			)
			(layer "F.Fab")
		)
		(fp_line
			(start -0.12065 0.2794)
			(end -0.12065 0.3048)
			(stroke
				(width 0.1)
				(type default)
			)
			(layer "F.Fab")
		)
		(fp_line
			(start 0.120396 0.2794)
			(end -0.12065 0.2794)
			(stroke
				(width 0.1)
				(type default)
			)
			(layer "F.Fab")
		)
		(fp_line
			(start -0.12065 -0.2794)
			(end 0.12065 -0.2794)
			(stroke
				(width 0.1)
				(type default)
			)
			(layer "F.Fab")
		)
		(fp_line
			(start 0.12065 -0.2794)
			(end 0.12065 -0.3048)
			(stroke
				(width 0.1)
				(type default)
			)
			(layer "F.Fab")
		)
		(fp_line
			(start 0.12065 -0.3048)
			(end 0.67945 -0.3048)
			(stroke
				(width 0.1)
				(type default)
			)
			(layer "F.Fab")
		)
		(fp_line
			(start 0.67945 -0.3048)
			(end 0.67945 0.3048)
			(stroke
				(width 0.1)
				(type default)
			)
			(layer "F.Fab")
		)
		(fp_line
			(start -0.67945 -0.305054)
			(end -0.12065 -0.305054)
			(stroke
				(width 0.1)
				(type default)
			)
			(layer "F.Fab")
		)
		(fp_line
			(start -0.12065 -0.305054)
			(end -0.12065 -0.2794)
			(stroke
				(width 0.1)
				(type default)
			)
			(layer "F.Fab")
		)
		(pad "1" smd circle
			(at -0.40005 0 270)
			(size 0 0)
			(layers "F.Cu" "F.Mask" "F.Paste")
			(net "P3V3_AUX")
		)
		(pad "2" smd circle
			(at 0.40005 0 270)
			(size 0 0)
			(layers "F.Cu" "F.Mask" "F.Paste")
			(net "P3V3_E1S_PWRGD_0_R")
		)
	)
)
